# TIMECARD (Time Appliance Project (Time Card)) — schematic netlist excerpt (pin names and nets, part order shuffled) for the footprints in the layout excerpt that follows; sources: Cadence DE-HDL packaged netlist, KiCad conversion of R4006-B0001-02_R01.brd

C193  CAPACITOR  0.01UF 25V 10%  pkg SMC_0201R  page 30 : \1\ = XP1R8V_PG_R ; \2\ = SG
SP46  NULL  pkg DUMMY  page 34
C309  CAPACITOR  0.1UF 25V 10%  pkg SMC_0402R_H022  page 33 : \1\ = XP3R3V_FT4232 ; \2\ = SG

(kicad_pcb
	(version 20260206)
	(generator "pcbnew")
	(generator_version "10.0")
	(general
		(thickness 1.6)
		(legacy_teardrops no)
	)
	(paper "A4")
	(title_block
		(title "timecard-production-celestica-r4006 — R4006-B0001-02_R01.brd")
		(comment 1 "Time Appliance Project (Time Card) / footprints 460-462 of 1113")
	)
	(layers
		(0 "F.Cu" signal "TOP")
		(4 "In1.Cu" signal "L02_GND1")
		(6 "In2.Cu" signal "L03_SIG1")
		(8 "In3.Cu" signal "L04_GND2")
		(10 "In4.Cu" signal "L05_VCC1")
		(12 "In5.Cu" signal "L06_VCC2")
		(14 "In6.Cu" signal "L07_GND3")
		(16 "In7.Cu" signal "L08_SIG2")
		(18 "In8.Cu" signal "L09_GND4")
		(2 "B.Cu" signal "BOTTOM")
		(9 "F.Adhes" user "F.Adhesive")
		(11 "B.Adhes" user "B.Adhesive")
		(13 "F.Paste" user "Package Geometry/Pastemask Top")
		(15 "B.Paste" user "Package Geometry/Pastemask Bottom")
		(5 "F.SilkS" user "Ref Des/Silkscreen Top")
		(7 "B.SilkS" user "Ref Des/Silkscreen Bottom")
		(1 "F.Mask" user "Board Geometry/Soldermask Top")
		(3 "B.Mask" user "Board Geometry/Soldermask Bottom")
		(17 "Dwgs.User" user "User.Drawings")
		(19 "Cmts.User" user "User.Comments")
		(21 "Eco1.User" user "User.Eco1")
		(23 "Eco2.User" user "User.Eco2")
		(25 "Edge.Cuts" user "Board Geometry/Outline")
		(27 "Margin" user)
		(31 "F.CrtYd" user "Package Geometry/Place Bound Top")
		(29 "B.CrtYd" user "Package Geometry/Place Bound Bottom")
		(35 "F.Fab" user "Ref Des/Assembly Top")
		(33 "B.Fab" user "Ref Des/Assembly Bottom")
	)
	(footprint ""
		(layer "F.Cu")
		(at 134.112 -69.215)
		(property "Reference" "C193"
			(at 0.889 -3.38963 0)
			(unlocked yes)
			(layer "F.SilkS")
			(effects
				(font
					(size 0.7874 0.5842)
					(thickness 0.1524)
				)
			)
		)
		(property "Value" "VAL*"
			(at 0.193548 2.13614 0)
			(unlocked yes)
			(layer "F.Fab")
			(hide yes)
			(effects
				(font
					(size 0.7874 0.5842)
					(thickness 0.1524)
				)
			)
		)
		(property "Tolerance" "TOL*"
			(at 0.216154 3.1496 0)
			(unlocked yes)
			(layer "Cmts.User")
			(hide yes)
			(effects
				(font
					(size 0.7874 0.5842)
					(thickness 0.1524)
				)
			)
		)
		(property "Device Type" "CAPACITOR-G104-0B103-EK,0.01UFA"
			(at 0.184404 1.180592 0)
			(unlocked yes)
			(layer "F.Fab")
			(hide yes)
			(effects
				(font
					(size 0.7874 0.5842)
					(thickness 0.1524)
				)
			)
		)
		(property "User Part Number" "PARTNUM*"
			(at 0.216154 4.185666 0)
			(unlocked yes)
			(layer "Cmts.User")
			(hide yes)
			(effects
				(font
					(size 0.7874 0.5842)
					(thickness 0.1524)
				)
			)
		)
		(duplicate_pad_numbers_are_jumpers no)
		(fp_line
			(start -0.671322 -0.4445)
			(end 0.671322 -0.4445)
			(stroke
				(width 0.1)
				(type default)
			)
			(layer "F.SilkS")
		)
		(fp_line
			(start -0.671322 0.4445)
			(end -0.671322 -0.4445)
			(stroke
				(width 0.1)
				(type default)
			)
			(layer "F.SilkS")
		)
		(fp_line
			(start 0.671322 -0.4445)
			(end 0.671322 0.4445)
			(stroke
				(width 0.1)
				(type default)
			)
			(layer "F.SilkS")
		)
		(fp_line
			(start 0.671322 0.4445)
			(end -0.671322 0.4445)
			(stroke
				(width 0.1)
				(type default)
			)
			(layer "F.SilkS")
		)
		(fp_rect
			(start 0.671322 0.4445)
			(end -0.671322 -0.4445)
			(stroke
				(width 0)
				(type default)
			)
			(fill no)
			(layer "F.CrtYd")
		)
		(fp_line
			(start -0.31496 -0.1651)
			(end -0.31496 0.1651)
			(stroke
				(width 0.1)
				(type default)
			)
			(layer "F.Fab")
		)
		(fp_line
			(start -0.31496 0.1651)
			(end 0.31496 0.1651)
			(stroke
				(width 0.1)
				(type default)
			)
			(layer "F.Fab")
		)
		(fp_line
			(start 0.31496 -0.1651)
			(end -0.31496 -0.1651)
			(stroke
				(width 0.1)
				(type default)
			)
			(layer "F.Fab")
		)
		(fp_line
			(start 0.31496 0.1651)
			(end 0.31496 -0.1651)
			(stroke
				(width 0.1)
				(type default)
			)
			(layer "F.Fab")
		)
		(pad "1" smd rect
			(at -0.264922 0)
			(size 0.3048 0.381)
			(layers "F.Cu" "F.Mask" "F.Paste")
			(net "XP1R8V_PG_R")
		)
		(pad "2" smd rect
			(at 0.264922 0)
			(size 0.3048 0.381)
			(layers "F.Cu" "F.Mask" "F.Paste")
			(net "SG")
		)
		(zone
			(layer "F.Cu")
			(hatch none 0.5)
			(connect_pads
				(clearance 0)
			)
			(min_thickness 0.25)
			(keepout
				(tracks allowed)
				(vias not_allowed)
				(pads allowed)
				(copperpour not_allowed)
				(footprints allowed)
			)
			(placement
				(enabled no)
				(sheetname "")
			)
			(fill
				(thermal_gap 0.5)
				(thermal_bridge_width 0.5)
				(island_removal_mode 0)
			)
			(polygon
				(pts
					(xy 134.224522 -69.0245) (xy 134.224522 -69.4055) (xy 133.999478 -69.4055) (xy 133.999478 -69.0245)
				)
			)
		)
	)
	(footprint ""
		(layer "F.Cu")
		(at 38.354 -80.899 90)
		(property "Reference" "C309"
			(at 3.556 -0.08763 90)
			(unlocked yes)
			(layer "F.SilkS")
			(effects
				(font
					(size 0.7874 0.5842)
					(thickness 0.1524)
				)
			)
		)
		(property "Value" "VAL*"
			(at 0.0762 2.067306 90)
			(unlocked yes)
			(layer "F.Fab")
			(hide yes)
			(effects
				(font
					(size 0.7874 0.5842)
					(thickness 0.1524)
				)
			)
		)
		(property "Tolerance" "TOL*"
			(at 0.0762 3.032506 90)
			(unlocked yes)
			(layer "Cmts.User")
			(hide yes)
			(effects
				(font
					(size 0.7874 0.5842)
					(thickness 0.1524)
				)
			)
		)
		(property "User Part Number" "PARTNUM*"
			(at 0.1016 4.023106 90)
			(unlocked yes)
			(layer "Cmts.User")
			(hide yes)
			(effects
				(font
					(size 0.7874 0.5842)
					(thickness 0.1524)
				)
			)
		)
		(property "Device Type" "CAPACITOR-G105-0B104-EK,0.1UF,A"
			(at 0.0508 1.127506 90)
			(unlocked yes)
			(layer "F.Fab")
			(hide yes)
			(effects
				(font
					(size 0.7874 0.5842)
					(thickness 0.1524)
				)
			)
		)
		(duplicate_pad_numbers_are_jumpers no)
		(fp_line
			(start 1.143 -0.5588)
			(end -1.143 -0.5588)
			(stroke
				(width 0.1)
				(type default)
			)
			(layer "F.SilkS")
		)
		(fp_line
			(start -1.143 -0.5588)
			(end -1.143 0.5588)
			(stroke
				(width 0.1)
				(type default)
			)
			(layer "F.SilkS")
		)
		(fp_line
			(start 1.143 0.5588)
			(end 1.143 -0.5588)
			(stroke
				(width 0.1)
				(type default)
			)
			(layer "F.SilkS")
		)
		(fp_line
			(start -1.143 0.5588)
			(end 1.143 0.5588)
			(stroke
				(width 0.1)
				(type default)
			)
			(layer "F.SilkS")
		)
		(fp_poly
			(pts
				(xy -1.143 0.5588) (xy 1.143 0.5588) (xy 1.143 -0.5588) (xy -1.143 -0.5588)
			)
			(stroke
				(width 0)
				(type default)
			)
			(fill no)
			(layer "F.CrtYd")
		)
		(fp_line
			(start 0.508 -0.3048)
			(end -0.508 -0.3048)
			(stroke
				(width 0.1)
				(type default)
			)
			(layer "F.Fab")
		)
		(fp_line
			(start -0.508 -0.3048)
			(end -0.508 0.3048)
			(stroke
				(width 0.1)
				(type default)
			)
			(layer "F.Fab")
		)
		(fp_line
			(start 0.508 0.3048)
			(end 0.508 -0.3048)
			(stroke
				(width 0.1)
				(type default)
			)
			(layer "F.Fab")
		)
		(fp_line
			(start -0.508 0.3048)
			(end 0.508 0.3048)
			(stroke
				(width 0.1)
				(type default)
			)
			(layer "F.Fab")
		)
		(pad "1" smd rect
			(at -0.5334 0 90)
			(size 0.7112 0.6096)
			(layers "F.Cu" "F.Mask" "F.Paste")
			(net "XP3R3V_FT4232")
		)
		(pad "2" smd rect
			(at 0.5334 0 90)
			(size 0.7112 0.6096)
			(layers "F.Cu" "F.Mask" "F.Paste")
			(net "SG")
		)
		(zone
			(layer "F.Cu")
			(hatch none 0.5)
			(connect_pads
				(clearance 0)
			)
			(min_thickness 0.25)
			(keepout
				(tracks not_allowed)
				(vias allowed)
				(pads allowed)
				(copperpour not_allowed)
				(footprints allowed)
			)
			(placement
				(enabled no)
				(sheetname "")
			)
			(fill
				(thermal_gap 0.5)
				(thermal_bridge_width 0.5)
				(island_removal_mode 0)
			)
			(polygon
				(pts
					(xy 38.6588 -80.8228) (xy 38.6588 -80.9752) (xy 38.0492 -80.9752) (xy 38.0492 -80.8228)
				)
			)
		)
		(zone
			(layer "F.Cu")
			(hatch none 0.5)
			(connect_pads
				(clearance 0)
			)
			(min_thickness 0.25)
			(keepout
				(tracks allowed)
				(vias not_allowed)
				(pads allowed)
				(copperpour not_allowed)
				(footprints allowed)
			)
			(placement
				(enabled no)
				(sheetname "")
			)
			(fill
				(thermal_gap 0.5)
				(thermal_bridge_width 0.5)
				(island_removal_mode 0)
			)
			(polygon
				(pts
					(xy 38.6588 -80.8228) (xy 38.6588 -80.9752) (xy 38.0492 -80.9752) (xy 38.0492 -80.8228)
				)
			)
		)
	)
	(footprint ""
		(layer "F.Cu")
		(at 57.15 -134.747)
		(property "Reference" "SP46"
			(at 0 0 0)
			(layer "F.SilkS")
			(hide yes)
			(effects
				(font
					(size 1.27 1.27)
				)
			)
		)
		(property "Value" ""
			(at 0 0 0)
			(layer "F.Fab")
			(effects
				(font
					(size 1.27 1.27)
				)
			)
		)
		(duplicate_pad_numbers_are_jumpers no)
	)
)
